(kicad_pcb
	(version 20260206)
	(generator "pcbnew")
	(generator_version "10.0")
	(general
		(thickness 1.6)
		(legacy_teardrops no)
	)
	(paper "A4")
	(title_block
		(title "Bryce Canyon_F.DPB_16315-1-OCP.brd")
		(comment 1 "Bryce Canyon / footprints 1191-1198 of 2223")
	)
	(layers
		(0 "F.Cu" signal "TOP")
		(4 "In1.Cu" signal "L2GND")
		(6 "In2.Cu" signal "L3")
		(8 "In3.Cu" signal "L4GND")
		(10 "In4.Cu" signal "L5")
		(12 "In5.Cu" signal "L6VCC")
		(14 "In6.Cu" signal "L7VCC")
		(16 "In7.Cu" signal "L8")
		(18 "In8.Cu" signal "L9GND")
		(20 "In9.Cu" signal "L10")
		(22 "In10.Cu" signal "L11GND")
		(2 "B.Cu" signal "BOTTOM")
		(9 "F.Adhes" user "F.Adhesive")
		(11 "B.Adhes" user "B.Adhesive")
		(13 "F.Paste" user "Package Geometry/Pastemask Top")
		(15 "B.Paste" user "Package Geometry/Pastemask Bottom")
		(5 "F.SilkS" user "Ref Des/Silkscreen Top")
		(7 "B.SilkS" user "Ref Des/Silkscreen Bottom")
		(1 "F.Mask" user "Board Geometry/Soldermask Top")
		(3 "B.Mask" user "Board Geometry/Soldermask Bottom")
		(17 "Dwgs.User" user "User.Drawings")
		(19 "Cmts.User" user "User.Comments")
		(21 "Eco1.User" user "User.Eco1")
		(23 "Eco2.User" user "User.Eco2")
		(25 "Edge.Cuts" user "Board Geometry/Outline")
		(27 "Margin" user)
		(31 "F.CrtYd" user "Package Geometry/Place Bound Top")
		(29 "B.CrtYd" user "Package Geometry/Place Bound Bottom")
		(35 "F.Fab" user "Ref Des/Assembly Top")
		(33 "B.Fab" user "Ref Des/Assembly Bottom")
	)
	(footprint ""
		(layer "F.Cu")
		(at 241.00663 -237.9345)
		(property "Reference" "C26"
			(at 0 0 0)
			(layer "F.SilkS")
			(hide yes)
			(effects
				(font
					(size 1.27 1.27)
				)
			)
		)
		(property "Value" "SCD1U16V2KX-3GP"
			(at 1.1811 -2.7051 0)
			(unlocked yes)
			(layer "F.Fab")
			(hide yes)
			(effects
				(font
					(size 1.016 1.016)
					(thickness 0.1524)
				)
			)
		)
		(property "Device Type" "C402H22"
			(at 1.1811 -4.2291 0)
			(unlocked yes)
			(layer "F.Fab")
			(hide yes)
			(effects
				(font
					(size 1.016 1.016)
					(thickness 0.1524)
				)
			)
		)
		(duplicate_pad_numbers_are_jumpers no)
		(fp_rect
			(start -0.4318 0.9525)
			(end 0.4318 -0.9525)
			(stroke
				(width 0)
				(type default)
			)
			(fill no)
			(layer "F.CrtYd")
		)
		(fp_rect
			(start -0.4318 0.9525)
			(end 0.4318 -0.9525)
			(stroke
				(width 0)
				(type default)
			)
			(fill no)
			(layer "F.Fab")
		)
		(pad "1" smd custom
			(at 0 -0.4445)
			(size 0.1524 0.1524)
			(layers "F.Cu" "F.Mask" "F.Paste")
			(net "GPIO_VCC_U8")
			(options
				(clearance outline)
				(anchor circle)
			)
			(primitives
				(gr_poly
					(pts
						(arc
							(start 0.3048 -0.2032)
							(mid 0.275042 -0.275042)
							(end 0.2032 -0.3048)
						)
						(arc
							(start -0.2032 -0.3048)
							(mid -0.275042 -0.275042)
							(end -0.3048 -0.2032)
						)
						(arc
							(start -0.3048 0.2032)
							(mid -0.275042 0.275042)
							(end -0.2032 0.3048)
						)
						(arc
							(start 0.2032 0.3048)
							(mid 0.275042 0.275042)
							(end 0.3048 0.2032)
						)
					)
					(width 0)
					(fill yes)
				)
			)
		)
		(pad "2" smd custom
			(at 0 0.4445)
			(size 0.1524 0.1524)
			(layers "F.Cu" "F.Mask" "F.Paste")
			(net "GND")
			(options
				(clearance outline)
				(anchor circle)
			)
			(primitives
				(gr_poly
					(pts
						(arc
							(start 0.3048 -0.2032)
							(mid 0.275042 -0.275042)
							(end 0.2032 -0.3048)
						)
						(arc
							(start -0.2032 -0.3048)
							(mid -0.275042 -0.275042)
							(end -0.3048 -0.2032)
						)
						(arc
							(start -0.3048 0.2032)
							(mid -0.275042 0.275042)
							(end -0.2032 0.3048)
						)
						(arc
							(start 0.2032 0.3048)
							(mid 0.275042 0.275042)
							(end 0.3048 0.2032)
						)
					)
					(width 0)
					(fill yes)
				)
			)
		)
	)
	(footprint ""
		(layer "F.Cu")
		(at 113.065052 -127.254)
		(property "Reference" "R296"
			(at 0 0 0)
			(layer "F.SilkS")
			(hide yes)
			(effects
				(font
					(size 1.27 1.27)
				)
			)
		)
		(property "Value" "91R3F-1-GP"
			(at -0.0254 -2.5146 0)
			(unlocked yes)
			(layer "F.Fab")
			(hide yes)
			(effects
				(font
					(size 1.016 1.016)
					(thickness 0.1524)
				)
			)
		)
		(property "Device Type" "R603H22"
			(at -0.0254 -4.0386 0)
			(unlocked yes)
			(layer "F.Fab")
			(hide yes)
			(effects
				(font
					(size 1.016 1.016)
					(thickness 0.1524)
				)
			)
		)
		(duplicate_pad_numbers_are_jumpers no)
		(fp_line
			(start -0.4826 0)
			(end -0.2032 0)
			(stroke
				(width 0.2032)
				(type default)
			)
			(layer "F.SilkS")
		)
		(fp_line
			(start 0.2032 0)
			(end 0.4826 0)
			(stroke
				(width 0.2032)
				(type default)
			)
			(layer "F.SilkS")
		)
		(fp_rect
			(start -0.5842 1.3335)
			(end 0.5842 -1.3335)
			(stroke
				(width 0)
				(type default)
			)
			(fill no)
			(layer "F.CrtYd")
		)
		(fp_rect
			(start -0.5842 1.3335)
			(end 0.5842 -1.3335)
			(stroke
				(width 0)
				(type default)
			)
			(fill no)
			(layer "F.Fab")
		)
		(pad "1" smd custom
			(at 0 -0.762)
			(size 0.2159 0.2159)
			(layers "F.Cu" "F.Mask" "F.Paste")
			(net "P5V_A_2")
			(options
				(clearance outline)
				(anchor circle)
			)
			(primitives
				(gr_poly
					(pts
						(arc
							(start -0.3302 -0.4318)
							(mid -0.402042 -0.402042)
							(end -0.4318 -0.3302)
						)
						(arc
							(start -0.4318 0.3302)
							(mid -0.402042 0.402042)
							(end -0.3302 0.4318)
						)
						(arc
							(start 0.3302 0.4318)
							(mid 0.402042 0.402042)
							(end 0.4318 0.3302)
						)
						(arc
							(start 0.4318 -0.3302)
							(mid 0.402042 -0.402042)
							(end 0.3302 -0.4318)
						)
					)
					(width 0)
					(fill yes)
				)
			)
		)
		(pad "2" smd custom
			(at 0 0.762)
			(size 0.2159 0.2159)
			(layers "F.Cu" "F.Mask" "F.Paste")
			(net "DRV_ACT_15")
			(options
				(clearance outline)
				(anchor circle)
			)
			(primitives
				(gr_poly
					(pts
						(arc
							(start -0.3302 -0.4318)
							(mid -0.402042 -0.402042)
							(end -0.4318 -0.3302)
						)
						(arc
							(start -0.4318 0.3302)
							(mid -0.402042 0.402042)
							(end -0.3302 0.4318)
						)
						(arc
							(start 0.3302 0.4318)
							(mid 0.402042 0.402042)
							(end 0.4318 0.3302)
						)
						(arc
							(start 0.4318 -0.3302)
							(mid 0.402042 -0.402042)
							(end 0.3302 -0.4318)
						)
					)
					(width 0)
					(fill yes)
				)
			)
		)
	)
	(footprint ""
		(layer "F.Cu")
		(at 22.071584 -159.926274 90)
		(property "Reference" "R417"
			(at 0 0 90)
			(layer "F.SilkS")
			(hide yes)
			(effects
				(font
					(size 1.27 1.27)
				)
			)
		)
		(property "Value" "0R2J-2-GP"
			(at 0.064008 -3.993896 90)
			(unlocked yes)
			(layer "F.Fab")
			(hide yes)
			(effects
				(font
					(size 1.016 1.016)
					(thickness 0.1524)
				)
			)
		)
		(property "Device Type" "R402H16"
			(at 0.064008 -5.517896 90)
			(unlocked yes)
			(layer "F.Fab")
			(hide yes)
			(effects
				(font
					(size 1.016 1.016)
					(thickness 0.1524)
				)
			)
		)
		(duplicate_pad_numbers_are_jumpers no)
		(fp_line
			(start 0.508 -0.9398)
			(end -0.508 -0.9398)
			(stroke
				(width 0.1524)
				(type default)
			)
			(layer "F.SilkS")
		)
		(fp_line
			(start -0.508 -0.9398)
			(end -0.508 0.9398)
			(stroke
				(width 0.1524)
				(type default)
			)
			(layer "F.SilkS")
		)
		(fp_rect
			(start -0.508 0.9398)
			(end 0.508 -0.9398)
			(stroke
				(width 0)
				(type default)
			)
			(fill no)
			(layer "F.CrtYd")
		)
		(fp_rect
			(start -0.508 0.9398)
			(end 0.508 -0.9398)
			(stroke
				(width 0)
				(type default)
			)
			(fill no)
			(layer "F.Fab")
		)
		(pad "1" smd custom
			(at 0 -0.4445 90)
			(size 0.1397 0.1397)
			(layers "F.Cu" "F.Mask" "F.Paste")
			(net "DRIVE_A_12_PWR")
			(options
				(clearance outline)
				(anchor circle)
			)
			(primitives
				(gr_poly
					(pts
						(arc
							(start -0.1778 -0.2794)
							(mid -0.249642 -0.249642)
							(end -0.2794 -0.1778)
						)
						(arc
							(start -0.2794 0.1778)
							(mid -0.249642 0.249642)
							(end -0.1778 0.2794)
						)
						(arc
							(start 0.1778 0.2794)
							(mid 0.249642 0.249642)
							(end 0.2794 0.1778)
						)
						(arc
							(start 0.2794 -0.1778)
							(mid 0.249642 -0.249642)
							(end 0.1778 -0.2794)
						)
					)
					(width 0)
					(fill yes)
				)
			)
		)
		(pad "2" smd custom
			(at 0 0.4445 90)
			(size 0.1397 0.1397)
			(layers "F.Cu" "F.Mask" "F.Paste")
			(net "SW_PWR_R_HDD12")
			(options
				(clearance outline)
				(anchor circle)
			)
			(primitives
				(gr_poly
					(pts
						(arc
							(start -0.1778 -0.2794)
							(mid -0.249642 -0.249642)
							(end -0.2794 -0.1778)
						)
						(arc
							(start -0.2794 0.1778)
							(mid -0.249642 0.249642)
							(end -0.1778 0.2794)
						)
						(arc
							(start 0.1778 0.2794)
							(mid 0.249642 0.249642)
							(end 0.2794 0.1778)
						)
						(arc
							(start 0.2794 -0.1778)
							(mid 0.249642 -0.249642)
							(end 0.1778 -0.2794)
						)
					)
					(width 0)
					(fill yes)
				)
			)
		)
	)
	(footprint ""
		(layer "F.Cu")
		(at 400.41195 -47.792894 90)
		(property "Reference" "D32"
			(at 0 0 90)
			(layer "F.SilkS")
			(hide yes)
			(effects
				(font
					(size 1.27 1.27)
				)
			)
		)
		(property "Value" "RB551V30-GP"
			(at 0 -6.7818 90)
			(unlocked yes)
			(layer "F.Fab")
			(hide yes)
			(effects
				(font
					(size 1.016 1.016)
					(thickness 0.1524)
				)
			)
		)
		(property "Device Type" "SOD323AKH38"
			(at 0 -8.6868 90)
			(unlocked yes)
			(layer "F.Fab")
			(hide yes)
			(effects
				(font
					(size 1.016 1.016)
					(thickness 0.1524)
				)
			)
		)
		(duplicate_pad_numbers_are_jumpers no)
		(fp_line
			(start 0.889 -1.9304)
			(end 0.889 2.159)
			(stroke
				(width 0.1524)
				(type default)
			)
			(layer "F.SilkS")
		)
		(fp_line
			(start -0.889 -1.9304)
			(end 0.889 -1.9304)
			(stroke
				(width 0.1524)
				(type default)
			)
			(layer "F.SilkS")
		)
		(fp_line
			(start 0.762 2.0574)
			(end -0.762 2.0574)
			(stroke
				(width 0.508)
				(type default)
			)
			(layer "F.SilkS")
		)
		(fp_line
			(start 0.889 2.159)
			(end -0.889 2.159)
			(stroke
				(width 0.1524)
				(type default)
			)
			(layer "F.SilkS")
		)
		(fp_line
			(start -0.889 2.159)
			(end -0.889 -1.9304)
			(stroke
				(width 0.1524)
				(type default)
			)
			(layer "F.SilkS")
		)
		(fp_rect
			(start -1.016 2.3114)
			(end 1.016 -2.0066)
			(stroke
				(width 0)
				(type default)
			)
			(fill no)
			(layer "F.CrtYd")
		)
		(fp_poly
			(pts
				(xy -1.016 -2.0066) (xy 1.016 -2.0066) (xy 1.016 2.3114) (xy -1.016 2.3114)
			)
			(stroke
				(width 0)
				(type default)
			)
			(fill no)
			(layer "F.Fab")
		)
		(pad "A" smd rect
			(at 0 -1.143 90)
			(size 0.5588 1.016)
			(layers "F.Cu" "F.Mask" "F.Paste")
			(net "SW_HDD_R32")
		)
		(pad "K" smd rect
			(at 0 1.143 90)
			(size 0.5588 1.016)
			(layers "F.Cu" "F.Mask" "F.Paste")
			(net "SW_HDD_N32")
		)
	)
	(footprint ""
		(layer "F.Cu")
		(at 236.819694 -244.146578)
		(property "Reference" "R73"
			(at 0 0 0)
			(layer "F.SilkS")
			(hide yes)
			(effects
				(font
					(size 1.27 1.27)
				)
			)
		)
		(property "Value" "4K7R2F-GP"
			(at 0.064008 -3.993896 0)
			(unlocked yes)
			(layer "F.Fab")
			(hide yes)
			(effects
				(font
					(size 1.016 1.016)
					(thickness 0.1524)
				)
			)
		)
		(property "Device Type" "R402H16"
			(at 0.064008 -5.517896 0)
			(unlocked yes)
			(layer "F.Fab")
			(hide yes)
			(effects
				(font
					(size 1.016 1.016)
					(thickness 0.1524)
				)
			)
		)
		(duplicate_pad_numbers_are_jumpers no)
		(fp_line
			(start -0.508 -0.9398)
			(end -0.508 0.9398)
			(stroke
				(width 0.1524)
				(type default)
			)
			(layer "F.SilkS")
		)
		(fp_line
			(start 0.508 -0.9398)
			(end -0.508 -0.9398)
			(stroke
				(width 0.1524)
				(type default)
			)
			(layer "F.SilkS")
		)
		(fp_rect
			(start -0.508 0.9398)
			(end 0.508 -0.9398)
			(stroke
				(width 0)
				(type default)
			)
			(fill no)
			(layer "F.CrtYd")
		)
		(fp_rect
			(start -0.508 0.9398)
			(end 0.508 -0.9398)
			(stroke
				(width 0)
				(type default)
			)
			(fill no)
			(layer "F.Fab")
		)
		(pad "1" smd custom
			(at 0 -0.4445)
			(size 0.1397 0.1397)
			(layers "F.Cu" "F.Mask" "F.Paste")
			(net "P3V3_STBY_A")
			(options
				(clearance outline)
				(anchor circle)
			)
			(primitives
				(gr_poly
					(pts
						(arc
							(start -0.1778 -0.2794)
							(mid -0.249642 -0.249642)
							(end -0.2794 -0.1778)
						)
						(arc
							(start -0.2794 0.1778)
							(mid -0.249642 0.249642)
							(end -0.1778 0.2794)
						)
						(arc
							(start 0.1778 0.2794)
							(mid 0.249642 0.249642)
							(end 0.2794 0.1778)
						)
						(arc
							(start 0.2794 -0.1778)
							(mid 0.249642 -0.249642)
							(end 0.1778 -0.2794)
						)
					)
					(width 0)
					(fill yes)
				)
			)
		)
		(pad "2" smd custom
			(at 0 0.4445)
			(size 0.1397 0.1397)
			(layers "F.Cu" "F.Mask" "F.Paste")
			(net "IO_EXP1_A1")
			(options
				(clearance outline)
				(anchor circle)
			)
			(primitives
				(gr_poly
					(pts
						(arc
							(start -0.1778 -0.2794)
							(mid -0.249642 -0.249642)
							(end -0.2794 -0.1778)
						)
						(arc
							(start -0.2794 0.1778)
							(mid -0.249642 0.249642)
							(end -0.1778 0.2794)
						)
						(arc
							(start 0.1778 0.2794)
							(mid 0.249642 0.249642)
							(end 0.2794 0.1778)
						)
						(arc
							(start 0.2794 -0.1778)
							(mid 0.249642 -0.249642)
							(end 0.1778 -0.2794)
						)
					)
					(width 0)
					(fill yes)
				)
			)
		)
	)
	(footprint ""
		(layer "F.Cu")
		(at 159.043878 -130.184398 -90)
		(property "Reference" "R523"
			(at 0 0 270)
			(layer "F.SilkS")
			(hide yes)
			(effects
				(font
					(size 1.27 1.27)
				)
			)
		)
		(property "Value" "4K7R2J-2-GP"
			(at 0.064008 -3.993896 270)
			(unlocked yes)
			(layer "F.Fab")
			(hide yes)
			(effects
				(font
					(size 1.016 1.016)
					(thickness 0.1524)
				)
			)
		)
		(property "Device Type" "R402H16"
			(at 0.064008 -5.517896 270)
			(unlocked yes)
			(layer "F.Fab")
			(hide yes)
			(effects
				(font
					(size 1.016 1.016)
					(thickness 0.1524)
				)
			)
		)
		(duplicate_pad_numbers_are_jumpers no)
		(fp_line
			(start -0.508 -0.9398)
			(end -0.508 0.9398)
			(stroke
				(width 0.1524)
				(type default)
			)
			(layer "F.SilkS")
		)
		(fp_line
			(start 0.508 -0.9398)
			(end -0.508 -0.9398)
			(stroke
				(width 0.1524)
				(type default)
			)
			(layer "F.SilkS")
		)
		(fp_rect
			(start -0.508 0.9398)
			(end 0.508 -0.9398)
			(stroke
				(width 0)
				(type default)
			)
			(fill no)
			(layer "F.CrtYd")
		)
		(fp_rect
			(start -0.508 0.9398)
			(end 0.508 -0.9398)
			(stroke
				(width 0)
				(type default)
			)
			(fill no)
			(layer "F.Fab")
		)
		(pad "1" smd custom
			(at 0 -0.4445 270)
			(size 0.1397 0.1397)
			(layers "F.Cu" "F.Mask" "F.Paste")
			(net "DRIVE_A_17_ACT")
			(options
				(clearance outline)
				(anchor circle)
			)
			(primitives
				(gr_poly
					(pts
						(arc
							(start -0.1778 -0.2794)
							(mid -0.249642 -0.249642)
							(end -0.2794 -0.1778)
						)
						(arc
							(start -0.2794 0.1778)
							(mid -0.249642 0.249642)
							(end -0.1778 0.2794)
						)
						(arc
							(start 0.1778 0.2794)
							(mid 0.249642 0.249642)
							(end 0.2794 0.1778)
						)
						(arc
							(start 0.2794 -0.1778)
							(mid 0.249642 -0.249642)
							(end 0.1778 -0.2794)
						)
					)
					(width 0)
					(fill yes)
				)
			)
		)
		(pad "2" smd custom
			(at 0 0.4445 270)
			(size 0.1397 0.1397)
			(layers "F.Cu" "F.Mask" "F.Paste")
			(net "GND")
			(options
				(clearance outline)
				(anchor circle)
			)
			(primitives
				(gr_poly
					(pts
						(arc
							(start -0.1778 -0.2794)
							(mid -0.249642 -0.249642)
							(end -0.2794 -0.1778)
						)
						(arc
							(start -0.2794 0.1778)
							(mid -0.249642 0.249642)
							(end -0.1778 0.2794)
						)
						(arc
							(start 0.1778 0.2794)
							(mid 0.249642 0.249642)
							(end 0.2794 0.1778)
						)
						(arc
							(start 0.2794 -0.1778)
							(mid 0.249642 -0.249642)
							(end 0.1778 -0.2794)
						)
					)
					(width 0)
					(fill yes)
				)
			)
		)
	)
	(footprint ""
		(layer "F.Cu")
		(at 266.987274 -148.925534 90)
		(property "Reference" "TP187"
			(at 0 0 90)
			(layer "F.SilkS")
			(hide yes)
			(effects
				(font
					(size 1.27 1.27)
				)
			)
		)
		(property "Value" "TPAD32-GP"
			(at -0.0508 -1.6764 90)
			(unlocked yes)
			(layer "F.Fab")
			(hide yes)
			(effects
				(font
					(size 1.016 1.016)
					(thickness 0.1524)
				)
			)
		)
		(property "Device Type" "TPAD32"
			(at -0.0508 -3.2004 90)
			(unlocked yes)
			(layer "F.Fab")
			(hide yes)
			(effects
				(font
					(size 1.016 1.016)
					(thickness 0.1524)
				)
			)
		)
		(duplicate_pad_numbers_are_jumpers no)
		(fp_poly
			(pts
				(arc
					(start 0 0.4064)
					(mid 0 -0.4064)
					(end 0 0.4064)
				)
			)
			(stroke
				(width 0)
				(type default)
			)
			(fill no)
			(layer "F.CrtYd")
		)
		(fp_poly
			(pts
				(arc
					(start 0 0.7112)
					(mid 0 -0.7112)
					(end 0 0.7112)
				)
			)
			(stroke
				(width 0)
				(type default)
			)
			(fill no)
			(layer "F.Fab")
		)
		(pad "1" smd circle
			(at 0 0 90)
			(size 0.8128 0.8128)
			(layers "F.Cu" "F.Mask" "F.Paste")
			(net "TP_COMP_B_KR_P0_RX_DP")
		)
	)
	(footprint ""
		(layer "F.Cu")
		(at 257.1496 -16.1544 90)
		(property "Reference" "R1044"
			(at 0 0 90)
			(layer "F.SilkS")
			(hide yes)
			(effects
				(font
					(size 1.27 1.27)
				)
			)
		)
		(property "Value" "100KR2F-L1-GP"
			(at 0.064008 -3.993896 90)
			(unlocked yes)
			(layer "F.Fab")
			(hide yes)
			(effects
				(font
					(size 1.016 1.016)
					(thickness 0.1524)
				)
			)
		)
		(property "Device Type" "R402H16"
			(at 0.064008 -5.517896 90)
			(unlocked yes)
			(layer "F.Fab")
			(hide yes)
			(effects
				(font
					(size 1.016 1.016)
					(thickness 0.1524)
				)
			)
		)
		(duplicate_pad_numbers_are_jumpers no)
		(fp_line
			(start 0.508 -0.9398)
			(end -0.508 -0.9398)
			(stroke
				(width 0.1524)
				(type default)
			)
			(layer "F.SilkS")
		)
		(fp_line
			(start -0.508 -0.9398)
			(end -0.508 0.9398)
			(stroke
				(width 0.1524)
				(type default)
			)
			(layer "F.SilkS")
		)
		(fp_rect
			(start -0.508 0.9398)
			(end 0.508 -0.9398)
			(stroke
				(width 0)
				(type default)
			)
			(fill no)
			(layer "F.CrtYd")
		)
		(fp_rect
			(start -0.508 0.9398)
			(end 0.508 -0.9398)
			(stroke
				(width 0)
				(type default)
			)
			(fill no)
			(layer "F.Fab")
		)
		(pad "1" smd custom
			(at 0 -0.4445 90)
			(size 0.1397 0.1397)
			(layers "F.Cu" "F.Mask" "F.Paste")
			(net "PCIE_COMP_A_TO_IOM_A_RST_4")
			(options
				(clearance outline)
				(anchor circle)
			)
			(primitives
				(gr_poly
					(pts
						(arc
							(start -0.1778 -0.2794)
							(mid -0.249642 -0.249642)
							(end -0.2794 -0.1778)
						)
						(arc
							(start -0.2794 0.1778)
							(mid -0.249642 0.249642)
							(end -0.1778 0.2794)
						)
						(arc
							(start 0.1778 0.2794)
							(mid 0.249642 0.249642)
							(end 0.2794 0.1778)
						)
						(arc
							(start 0.2794 -0.1778)
							(mid 0.249642 -0.249642)
							(end 0.1778 -0.2794)
						)
					)
					(width 0)
					(fill yes)
				)
			)
		)
		(pad "2" smd custom
			(at 0 0.4445 90)
			(size 0.1397 0.1397)
			(layers "F.Cu" "F.Mask" "F.Paste")
			(net "GND")
			(options
				(clearance outline)
				(anchor circle)
			)
			(primitives
				(gr_poly
					(pts
						(arc
							(start -0.1778 -0.2794)
							(mid -0.249642 -0.249642)
							(end -0.2794 -0.1778)
						)
						(arc
							(start -0.2794 0.1778)
							(mid -0.249642 0.249642)
							(end -0.1778 0.2794)
						)
						(arc
							(start 0.1778 0.2794)
							(mid 0.249642 0.249642)
							(end 0.2794 0.1778)
						)
						(arc
							(start 0.2794 -0.1778)
							(mid 0.249642 -0.249642)
							(end 0.1778 -0.2794)
						)
					)
					(width 0)
					(fill yes)
				)
			)
		)
	)
)
